(kicad_pcb
	(version 20260206)
	(generator "pcbnew")
	(generator_version "10.0")
	(general
		(thickness 1.6)
		(legacy_teardrops no)
	)
	(paper "A4")
	(title_block
		(title "Bryce Canyon_R.DPB_16317-1_OCP.brd")
		(comment 1 "Bryce Canyon / footprints 1634-1638 of 2099")
	)
	(layers
		(0 "F.Cu" signal "TOP")
		(4 "In1.Cu" signal "L2GND")
		(6 "In2.Cu" signal "L3")
		(8 "In3.Cu" signal "L4VCC")
		(10 "In4.Cu" signal "L5VCC")
		(12 "In5.Cu" signal "L6")
		(14 "In6.Cu" signal "L7GND")
		(2 "B.Cu" signal "BOTTOM")
		(9 "F.Adhes" user "F.Adhesive")
		(11 "B.Adhes" user "B.Adhesive")
		(13 "F.Paste" user "Package Geometry/Pastemask Top")
		(15 "B.Paste" user "Package Geometry/Pastemask Bottom")
		(5 "F.SilkS" user "Ref Des/Silkscreen Top")
		(7 "B.SilkS" user "Ref Des/Silkscreen Bottom")
		(1 "F.Mask" user "Board Geometry/Soldermask Top")
		(3 "B.Mask" user "Board Geometry/Soldermask Bottom")
		(17 "Dwgs.User" user "User.Drawings")
		(19 "Cmts.User" user "User.Comments")
		(21 "Eco1.User" user "User.Eco1")
		(23 "Eco2.User" user "User.Eco2")
		(25 "Edge.Cuts" user "Board Geometry/Outline")
		(27 "Margin" user)
		(31 "F.CrtYd" user "Package Geometry/Place Bound Top")
		(29 "B.CrtYd" user "Package Geometry/Place Bound Bottom")
		(35 "F.Fab" user "Ref Des/Assembly Top")
		(33 "B.Fab" user "Ref Des/Assembly Bottom")
	)
	(footprint ""
		(layer "F.Cu")
		(at 244.9322 -341.4268)
		(property "Reference" "R1047"
			(at 0 0 0)
			(layer "F.SilkS")
			(hide yes)
			(effects
				(font
					(size 1.27 1.27)
				)
			)
		)
		(property "Value" "D0003R4026F-GP"
			(at -6.737858 -1.79959 0)
			(unlocked yes)
			(layer "F.Fab")
			(hide yes)
			(effects
				(font
					(size 1.016 1.016)
					(thickness 0.1524)
				)
			)
		)
		(property "Device Type" "RL4026-4PH149"
			(at -6.737858 -3.32359 0)
			(unlocked yes)
			(layer "F.Fab")
			(hide yes)
			(effects
				(font
					(size 1.016 1.016)
					(thickness 0.1524)
				)
			)
		)
		(duplicate_pad_numbers_are_jumpers no)
		(fp_line
			(start -5.6769 2.4765)
			(end -5.6769 4.0259)
			(stroke
				(width 0.3302)
				(type default)
			)
			(layer "F.SilkS")
		)
		(fp_line
			(start -5.6769 4.0259)
			(end -4.1402 4.0259)
			(stroke
				(width 0.3302)
				(type default)
			)
			(layer "F.SilkS")
		)
		(fp_line
			(start -5.588 -3.937)
			(end 5.588 -3.937)
			(stroke
				(width 0.1524)
				(type default)
			)
			(layer "F.SilkS")
		)
		(fp_line
			(start -5.588 3.937)
			(end -5.588 -3.937)
			(stroke
				(width 0.1524)
				(type default)
			)
			(layer "F.SilkS")
		)
		(fp_line
			(start 5.588 -3.937)
			(end 5.588 3.937)
			(stroke
				(width 0.1524)
				(type default)
			)
			(layer "F.SilkS")
		)
		(fp_line
			(start 5.588 3.937)
			(end -5.588 3.937)
			(stroke
				(width 0.1524)
				(type default)
			)
			(layer "F.SilkS")
		)
		(fp_poly
			(pts
				(xy -4.703572 3.998468) (xy -5.289804 4.5847) (xy -4.11734 4.5847)
			)
			(stroke
				(width 0)
				(type default)
			)
			(fill yes)
			(layer "F.SilkS")
		)
		(fp_rect
			(start -5.0546 3.302)
			(end 5.0546 -3.302)
			(stroke
				(width 0)
				(type default)
			)
			(fill no)
			(layer "F.CrtYd")
		)
		(fp_poly
			(pts
				(xy -5.842 4.191) (xy -5.842 -4.191) (xy 5.842 -4.191) (xy 5.842 -0.00635) (xy 5.0546 -0.00635)
				(xy 5.0546 -3.302) (xy -5.0546 -3.302) (xy -5.0546 3.302) (xy 5.0546 3.302) (xy 5.0546 0.00635)
				(xy 5.842 0.00635) (xy 5.842 4.191)
			)
			(stroke
				(width 0)
				(type default)
			)
			(fill no)
			(layer "F.CrtYd")
		)
		(fp_rect
			(start -5.842 4.191)
			(end 5.842 -4.191)
			(stroke
				(width 0)
				(type default)
			)
			(fill no)
			(layer "F.Fab")
		)
		(pad "1" smd rect
			(at -4.115054 0.890016)
			(size 2.4384 5.588)
			(layers "F.Cu" "F.Mask" "F.Paste")
			(net "P12V_IN")
		)
		(pad "2" smd rect
			(at 4.115054 0.890016)
			(size 2.4384 5.588)
			(layers "F.Cu" "F.Mask" "F.Paste")
			(net "MB3_P12V_IN_R")
		)
		(pad "3" smd rect
			(at -4.115054 -3.245104)
			(size 2.4384 0.889)
			(layers "F.Cu" "F.Mask" "F.Paste")
			(net "MB3_CM_SENSE_R1_P")
		)
		(pad "4" smd rect
			(at 4.115054 -3.245104)
			(size 2.4384 0.889)
			(layers "F.Cu" "F.Mask" "F.Paste")
			(net "MB3_CM_SENSE_R1_N")
		)
		(zone
			(layer "F.Cu")
			(hatch none 0.5)
			(connect_pads
				(clearance 0)
			)
			(min_thickness 0.25)
			(keepout
				(tracks allowed)
				(vias not_allowed)
				(pads allowed)
				(copperpour not_allowed)
				(footprints allowed)
			)
			(placement
				(enabled no)
				(sheetname "")
			)
			(fill
				(thermal_gap 0.5)
				(thermal_bridge_width 0.5)
				(island_removal_mode 0)
			)
			(polygon
				(pts
					(xy 239.597946 -344.227404) (xy 239.597946 -343.330784) (xy 242.036346 -343.330784) (xy 242.036346 -344.227404)
				)
			)
		)
		(zone
			(layer "F.Cu")
			(hatch none 0.5)
			(connect_pads
				(clearance 0)
			)
			(min_thickness 0.25)
			(keepout
				(tracks not_allowed)
				(vias allowed)
				(pads allowed)
				(copperpour not_allowed)
				(footprints allowed)
			)
			(placement
				(enabled no)
				(sheetname "")
			)
			(fill
				(thermal_gap 0.5)
				(thermal_bridge_width 0.5)
				(island_removal_mode 0)
			)
			(polygon
				(pts
					(xy 239.597946 -343.330784) (xy 242.036346 -343.330784) (xy 242.036346 -344.227404) (xy 239.597946 -344.227404)
				)
			)
		)
		(zone
			(layer "F.Cu")
			(hatch none 0.5)
			(connect_pads
				(clearance 0)
			)
			(min_thickness 0.25)
			(keepout
				(tracks allowed)
				(vias not_allowed)
				(pads allowed)
				(copperpour not_allowed)
				(footprints allowed)
			)
			(placement
				(enabled no)
				(sheetname "")
			)
			(fill
				(thermal_gap 0.5)
				(thermal_bridge_width 0.5)
				(island_removal_mode 0)
			)
			(polygon
				(pts
					(xy 247.828054 -344.227404) (xy 247.828054 -343.330784) (xy 250.266454 -343.330784) (xy 250.266454 -344.227404)
				)
			)
		)
		(zone
			(layer "F.Cu")
			(hatch none 0.5)
			(connect_pads
				(clearance 0)
			)
			(min_thickness 0.25)
			(keepout
				(tracks not_allowed)
				(vias allowed)
				(pads allowed)
				(copperpour not_allowed)
				(footprints allowed)
			)
			(placement
				(enabled no)
				(sheetname "")
			)
			(fill
				(thermal_gap 0.5)
				(thermal_bridge_width 0.5)
				(island_removal_mode 0)
			)
			(polygon
				(pts
					(xy 247.828054 -343.330784) (xy 250.266454 -343.330784) (xy 250.266454 -344.227404) (xy 247.828054 -344.227404)
				)
			)
		)
	)
	(footprint ""
		(layer "F.Cu")
		(at 239.859566 -140.050266 90)
		(property "Reference" "R444"
			(at 0 0 90)
			(layer "F.SilkS")
			(hide yes)
			(effects
				(font
					(size 1.27 1.27)
				)
			)
		)
		(property "Value" "1KR2J-1-GP"
			(at 0.064008 -3.993896 90)
			(unlocked yes)
			(layer "F.Fab")
			(hide yes)
			(effects
				(font
					(size 1.016 1.016)
					(thickness 0.1524)
				)
			)
		)
		(property "Device Type" "R402H16"
			(at 0.064008 -5.517896 90)
			(unlocked yes)
			(layer "F.Fab")
			(hide yes)
			(effects
				(font
					(size 1.016 1.016)
					(thickness 0.1524)
				)
			)
		)
		(duplicate_pad_numbers_are_jumpers no)
		(fp_line
			(start 0.508 -0.9398)
			(end -0.508 -0.9398)
			(stroke
				(width 0.1524)
				(type default)
			)
			(layer "F.SilkS")
		)
		(fp_line
			(start -0.508 -0.9398)
			(end -0.508 0.9398)
			(stroke
				(width 0.1524)
				(type default)
			)
			(layer "F.SilkS")
		)
		(fp_rect
			(start -0.508 0.9398)
			(end 0.508 -0.9398)
			(stroke
				(width 0)
				(type default)
			)
			(fill no)
			(layer "F.CrtYd")
		)
		(fp_rect
			(start -0.508 0.9398)
			(end 0.508 -0.9398)
			(stroke
				(width 0)
				(type default)
			)
			(fill no)
			(layer "F.Fab")
		)
		(pad "1" smd custom
			(at 0 -0.4445 90)
			(size 0.1397 0.1397)
			(layers "F.Cu" "F.Mask" "F.Paste")
			(net "P3V3_STBY_B")
			(options
				(clearance outline)
				(anchor circle)
			)
			(primitives
				(gr_poly
					(pts
						(arc
							(start -0.1778 -0.2794)
							(mid -0.249642 -0.249642)
							(end -0.2794 -0.1778)
						)
						(arc
							(start -0.2794 0.1778)
							(mid -0.249642 0.249642)
							(end -0.1778 0.2794)
						)
						(arc
							(start 0.1778 0.2794)
							(mid 0.249642 0.249642)
							(end 0.2794 0.1778)
						)
						(arc
							(start 0.2794 -0.1778)
							(mid 0.249642 -0.249642)
							(end 0.1778 -0.2794)
						)
					)
					(width 0)
					(fill yes)
				)
			)
		)
		(pad "2" smd custom
			(at 0 0.4445 90)
			(size 0.1397 0.1397)
			(layers "F.Cu" "F.Mask" "F.Paste")
			(net "I2C_SCC_B_SCL_BUF")
			(options
				(clearance outline)
				(anchor circle)
			)
			(primitives
				(gr_poly
					(pts
						(arc
							(start -0.1778 -0.2794)
							(mid -0.249642 -0.249642)
							(end -0.2794 -0.1778)
						)
						(arc
							(start -0.2794 0.1778)
							(mid -0.249642 0.249642)
							(end -0.1778 0.2794)
						)
						(arc
							(start 0.1778 0.2794)
							(mid 0.249642 0.249642)
							(end 0.2794 0.1778)
						)
						(arc
							(start 0.2794 -0.1778)
							(mid 0.249642 -0.249642)
							(end 0.1778 -0.2794)
						)
					)
					(width 0)
					(fill yes)
				)
			)
		)
	)
	(footprint ""
		(layer "F.Cu")
		(at 51.689 -262.001 -90)
		(property "Reference" "C45"
			(at 0 0 270)
			(layer "F.SilkS")
			(hide yes)
			(effects
				(font
					(size 1.27 1.27)
				)
			)
		)
		(property "Value" "SC10U16V6KX-2GP"
			(at -0.0762 -5.1308 270)
			(unlocked yes)
			(layer "F.Fab")
			(hide yes)
			(effects
				(font
					(size 1.016 1.016)
					(thickness 0.1524)
				)
			)
		)
		(property "Device Type" "C1206H71"
			(at -0.127 -6.6548 270)
			(unlocked yes)
			(layer "F.Fab")
			(hide yes)
			(effects
				(font
					(size 1.016 1.016)
					(thickness 0.1524)
				)
			)
		)
		(duplicate_pad_numbers_are_jumpers no)
		(fp_line
			(start -1.016 2.2352)
			(end -1.016 0.8382)
			(stroke
				(width 0.1524)
				(type default)
			)
			(layer "F.SilkS")
		)
		(fp_line
			(start 1.016 2.2352)
			(end -1.016 2.2352)
			(stroke
				(width 0.1524)
				(type default)
			)
			(layer "F.SilkS")
		)
		(fp_line
			(start 1.016 0.8382)
			(end 1.016 2.2352)
			(stroke
				(width 0.1524)
				(type default)
			)
			(layer "F.SilkS")
		)
		(fp_line
			(start -1.016 -0.8382)
			(end -1.016 -2.2352)
			(stroke
				(width 0.1524)
				(type default)
			)
			(layer "F.SilkS")
		)
		(fp_line
			(start -1.016 -2.2352)
			(end 1.016 -2.2352)
			(stroke
				(width 0.1524)
				(type default)
			)
			(layer "F.SilkS")
		)
		(fp_line
			(start 1.016 -2.2352)
			(end 1.016 -0.8382)
			(stroke
				(width 0.1524)
				(type default)
			)
			(layer "F.SilkS")
		)
		(fp_rect
			(start -1.0922 2.3114)
			(end 1.0922 -2.3114)
			(stroke
				(width 0)
				(type default)
			)
			(fill no)
			(layer "F.CrtYd")
		)
		(fp_poly
			(pts
				(xy 1.0922 -2.3114) (xy 1.0922 2.3114) (xy -1.0922 2.3114) (xy -1.0922 -2.3114)
			)
			(stroke
				(width 0)
				(type default)
			)
			(fill no)
			(layer "F.Fab")
		)
		(pad "1" smd rect
			(at 0 -1.397 270)
			(size 1.651 1.27)
			(layers "F.Cu" "F.Mask" "F.Paste")
			(net "P5V_HDD1")
		)
		(pad "2" smd rect
			(at 0 1.397 270)
			(size 1.651 1.27)
			(layers "F.Cu" "F.Mask" "F.Paste")
			(net "GND")
		)
	)
	(footprint ""
		(layer "F.Cu")
		(at 229.49916 -226.431856 180)
		(property "Reference" "U8"
			(at 0 0 180)
			(layer "F.SilkS")
			(hide yes)
			(effects
				(font
					(size 1.27 1.27)
				)
			)
		)
		(property "Value" "TCA9555PWR-GP"
			(at 0 -6.9342 180)
			(unlocked yes)
			(layer "F.Fab")
			(hide yes)
			(effects
				(font
					(size 1.016 1.016)
					(thickness 0.1524)
				)
			)
		)
		(property "Device Type" "TSOIC24H48"
			(at 0 -8.5852 180)
			(unlocked yes)
			(layer "F.Fab")
			(hide yes)
			(effects
				(font
					(size 1.016 1.016)
					(thickness 0.1524)
				)
			)
		)
		(duplicate_pad_numbers_are_jumpers no)
		(fp_line
			(start 3.81 1.397)
			(end -4.2291 1.397)
			(stroke
				(width 0.1524)
				(type default)
			)
			(layer "F.SilkS")
		)
		(fp_line
			(start 3.81 -1.397)
			(end 3.81 1.397)
			(stroke
				(width 0.1524)
				(type default)
			)
			(layer "F.SilkS")
		)
		(fp_line
			(start -3.429 0)
			(end -4.2291 0.8001)
			(stroke
				(width 0.1524)
				(type default)
			)
			(layer "F.SilkS")
		)
		(fp_line
			(start -4.22656 3.81)
			(end -4.2291 1.397)
			(stroke
				(width 0.508)
				(type default)
			)
			(layer "F.SilkS")
		)
		(fp_line
			(start -4.2291 3.937)
			(end -4.2291 -1.397)
			(stroke
				(width 0.1524)
				(type default)
			)
			(layer "F.SilkS")
		)
		(fp_line
			(start -4.2291 -0.8001)
			(end -3.429 0)
			(stroke
				(width 0.1524)
				(type default)
			)
			(layer "F.SilkS")
		)
		(fp_line
			(start -4.2291 -1.397)
			(end 3.81 -1.397)
			(stroke
				(width 0.1524)
				(type default)
			)
			(layer "F.SilkS")
		)
		(fp_poly
			(pts
				(xy -3.90652 -1.8542) (xy 3.90652 -1.8542) (xy 3.90652 1.8542) (xy -3.90652 1.8542)
			)
			(stroke
				(width 0)
				(type default)
			)
			(fill yes)
			(layer "F.SilkS")
		)
		(fp_poly
			(pts
				(xy -4.2164 3.81) (xy 4.2164 3.81) (xy 4.22656 -3.81) (xy -4.2164 -3.81)
			)
			(stroke
				(width 0)
				(type default)
			)
			(fill no)
			(layer "F.CrtYd")
		)
		(fp_poly
			(pts
				(xy -4.22656 -3.81) (xy 4.22656 -3.81) (xy 4.22656 3.81) (xy -4.22656 3.81)
			)
			(stroke
				(width 0)
				(type default)
			)
			(fill no)
			(layer "F.Fab")
		)
		(pad "1" smd rect
			(at -3.57632 2.8194 180)
			(size 0.3556 1.524)
			(layers "F.Cu" "F.Mask" "F.Paste")
			(net "IO_EXP1_INT_N")
		)
		(pad "2" smd rect
			(at -2.92608 2.8194 180)
			(size 0.3556 1.524)
			(layers "F.Cu" "F.Mask" "F.Paste")
			(net "IO_EXP1_A1")
		)
		(pad "3" smd rect
			(at -2.27584 2.8194 180)
			(size 0.3556 1.524)
			(layers "F.Cu" "F.Mask" "F.Paste")
			(net "IO_EXP1_A2")
		)
		(pad "4" smd rect
			(at -1.6256 2.8194 180)
			(size 0.3556 1.524)
			(layers "F.Cu" "F.Mask" "F.Paste")
			(net "DRIVE_B_0_PWR")
		)
		(pad "5" smd rect
			(at -0.97536 2.8194 180)
			(size 0.3556 1.524)
			(layers "F.Cu" "F.Mask" "F.Paste")
			(net "DRIVE_B_1_PWR")
		)
		(pad "6" smd rect
			(at -0.32512 2.8194 180)
			(size 0.3556 1.524)
			(layers "F.Cu" "F.Mask" "F.Paste")
			(net "DRIVE_B_2_PWR")
		)
		(pad "7" smd rect
			(at 0.32512 2.8194 180)
			(size 0.3556 1.524)
			(layers "F.Cu" "F.Mask" "F.Paste")
			(net "DRIVE_B_3_PWR")
		)
		(pad "8" smd rect
			(at 0.97536 2.8194 180)
			(size 0.3556 1.524)
			(layers "F.Cu" "F.Mask" "F.Paste")
			(net "DRIVE_B_4_PWR")
		)
		(pad "9" smd rect
			(at 1.6256 2.8194 180)
			(size 0.3556 1.524)
			(layers "F.Cu" "F.Mask" "F.Paste")
			(net "DRIVE_B_5_PWR")
		)
		(pad "10" smd rect
			(at 2.27584 2.8194 180)
			(size 0.3556 1.524)
			(layers "F.Cu" "F.Mask" "F.Paste")
			(net "DRIVE_B_6_PWR")
		)
		(pad "11" smd rect
			(at 2.92608 2.8194 180)
			(size 0.3556 1.524)
			(layers "F.Cu" "F.Mask" "F.Paste")
			(net "DRIVE_B_7_PWR")
		)
		(pad "12" smd rect
			(at 3.57632 2.8194 180)
			(size 0.3556 1.524)
			(layers "F.Cu" "F.Mask" "F.Paste")
			(net "GND")
		)
		(pad "13" smd rect
			(at 3.57632 -2.8194 180)
			(size 0.3556 1.524)
			(layers "F.Cu" "F.Mask" "F.Paste")
			(net "DRIVE_B_8_PWR")
		)
		(pad "14" smd rect
			(at 2.92608 -2.8194 180)
			(size 0.3556 1.524)
			(layers "F.Cu" "F.Mask" "F.Paste")
			(net "DRIVE_B_9_PWR")
		)
		(pad "15" smd rect
			(at 2.27584 -2.8194 180)
			(size 0.3556 1.524)
			(layers "F.Cu" "F.Mask" "F.Paste")
			(net "DRIVE_B_10_PWR")
		)
		(pad "16" smd rect
			(at 1.6256 -2.8194 180)
			(size 0.3556 1.524)
			(layers "F.Cu" "F.Mask" "F.Paste")
			(net "DRIVE_B_11_PWR")
		)
		(pad "17" smd rect
			(at 0.97536 -2.8194 180)
			(size 0.3556 1.524)
			(layers "F.Cu" "F.Mask" "F.Paste")
			(net "DRIVE_B_12_PWR")
		)
		(pad "18" smd rect
			(at 0.32512 -2.8194 180)
			(size 0.3556 1.524)
			(layers "F.Cu" "F.Mask" "F.Paste")
			(net "DRIVE_B_13_PWR")
		)
		(pad "19" smd rect
			(at -0.32512 -2.8194 180)
			(size 0.3556 1.524)
			(layers "F.Cu" "F.Mask" "F.Paste")
			(net "DRIVE_B_14_PWR")
		)
		(pad "20" smd rect
			(at -0.97536 -2.8194 180)
			(size 0.3556 1.524)
			(layers "F.Cu" "F.Mask" "F.Paste")
			(net "DRIVE_B_15_PWR")
		)
		(pad "21" smd rect
			(at -1.6256 -2.8194 180)
			(size 0.3556 1.524)
			(layers "F.Cu" "F.Mask" "F.Paste")
			(net "IO_EXP1_A0")
		)
		(pad "22" smd rect
			(at -2.27584 -2.8194 180)
			(size 0.3556 1.524)
			(layers "F.Cu" "F.Mask" "F.Paste")
			(net "IO_EXP1_SCL")
		)
		(pad "23" smd rect
			(at -2.92608 -2.8194 180)
			(size 0.3556 1.524)
			(layers "F.Cu" "F.Mask" "F.Paste")
			(net "IO_EXP1_SDA")
		)
		(pad "24" smd rect
			(at -3.57632 -2.8194 180)
			(size 0.3556 1.524)
			(layers "F.Cu" "F.Mask" "F.Paste")
			(net "GPIO_VCC_U8")
		)
	)
	(footprint ""
		(layer "F.Cu")
		(at 431.927 -18.796 90)
		(property "Reference" "D33"
			(at 0 0 90)
			(layer "F.SilkS")
			(hide yes)
			(effects
				(font
					(size 1.27 1.27)
				)
			)
		)
		(property "Value" "RB551V30-GP"
			(at 0 -6.7818 90)
			(unlocked yes)
			(layer "F.Fab")
			(hide yes)
			(effects
				(font
					(size 1.016 1.016)
					(thickness 0.1524)
				)
			)
		)
		(property "Device Type" "SOD323AKH38"
			(at 0 -8.6868 90)
			(unlocked yes)
			(layer "F.Fab")
			(hide yes)
			(effects
				(font
					(size 1.016 1.016)
					(thickness 0.1524)
				)
			)
		)
		(duplicate_pad_numbers_are_jumpers no)
		(fp_line
			(start 0.889 -1.9304)
			(end 0.889 2.159)
			(stroke
				(width 0.1524)
				(type default)
			)
			(layer "F.SilkS")
		)
		(fp_line
			(start -0.889 -1.9304)
			(end 0.889 -1.9304)
			(stroke
				(width 0.1524)
				(type default)
			)
			(layer "F.SilkS")
		)
		(fp_line
			(start 0.762 2.0574)
			(end -0.762 2.0574)
			(stroke
				(width 0.508)
				(type default)
			)
			(layer "F.SilkS")
		)
		(fp_line
			(start 0.889 2.159)
			(end -0.889 2.159)
			(stroke
				(width 0.1524)
				(type default)
			)
			(layer "F.SilkS")
		)
		(fp_line
			(start -0.889 2.159)
			(end -0.889 -1.9304)
			(stroke
				(width 0.1524)
				(type default)
			)
			(layer "F.SilkS")
		)
		(fp_rect
			(start -1.016 2.3114)
			(end 1.016 -2.0066)
			(stroke
				(width 0)
				(type default)
			)
			(fill no)
			(layer "F.CrtYd")
		)
		(fp_poly
			(pts
				(xy -1.016 -2.0066) (xy 1.016 -2.0066) (xy 1.016 2.3114) (xy -1.016 2.3114)
			)
			(stroke
				(width 0)
				(type default)
			)
			(fill no)
			(layer "F.Fab")
		)
		(pad "A" smd rect
			(at 0 -1.143 90)
			(size 0.5588 1.016)
			(layers "F.Cu" "F.Mask" "F.Paste")
			(net "SW_HDD_R33")
		)
		(pad "K" smd rect
			(at 0 1.143 90)
			(size 0.5588 1.016)
			(layers "F.Cu" "F.Mask" "F.Paste")
			(net "SW_HDD_N33")
		)
	)
)
